FILE_TYPE = CONNECTIVITY;
{Allegro Design Entry HDL 17.2-2016 S081 (4005846) 1/11/2022}
"PAGE_NUMBER" = 274;
0"NC";
1"GND\g";
2"GND\g";
3"GND\g";
4"GND\g";
5"GND\g";
6"P3V3_AUX\g";
7"P12V_AUX\g";
8"P12V_AUX\g";
9"GND\g";
10"P12V_AUX\g";
11"PWRGD_DSW_PWROK";
12"NC_U205_OUTB";
13"PWRGD_DSW_PWROK_R4";
14"NC_U205_INB-";
15"A_HSC_INAP";
16"A_P12V_STBY_FP_TRIGGER";
17"IRQ_UV_DETECT_N";
18"A_P12V_STBY_FPH_GATE";
19"FM_UV_ADR_TRIGGER_N";
20"A_P12V_STBY_ADR_TRIGGER";
21"P12V_AUX\g";
22"GND\g";
23"P3V3_AUX\g";
24"GND\g";
25"P3V3_AUX\g";
%"Q_CAP"
"1","(-1725,0)","0","pure_quanta","I103";
;
LOCATION"C1562"
$SEC"1"
CDS_SEC"1"
PACK_TYPE"0402"
VOLTAGE"25V"
VALUE"0.1UF"
PART_NUMBER"CH4104K1B00"
MATERIAL"X7R"
TOLERANCE"10%"
CDS_LIB"pure_quanta";
"B"
$PN"2"9;
"A"
$PN"1"25;
%"Q_CAP"
"1","(-1325,2200)","0","pure_quanta","I104";
;
LOCATION"C1561"
$SEC"1"
CDS_SEC"1"
PACK_TYPE"0402"
MATERIAL"X7R"
TOLERANCE"10%"
VOLTAGE"25V"
VALUE"0.1UF"
PART_NUMBER"CH4104K1B00"
CDS_LIB"pure_quanta";
"B"
$PN"2"4;
"A"
$PN"1"21;
%"UNIVERSAL_GND"
"1","(-2500,-500)","0","pure_quanta_power","I105";
;
HDL_POWER"GND"
CDS_LIB"pure_quanta_power";
"A"1;
%"UNIVERSAL_GND"
"1","(-2625,1150)","0","pure_quanta_power","I106";
;
CDS_LIB"pure_quanta_power"
HDL_POWER"GND";
"A"2;
%"UNIVERSAL_GND"
"1","(-2025,1150)","0","pure_quanta_power","I107";
;
HDL_POWER"GND"
CDS_LIB"pure_quanta_power";
"A"3;
%"UNIVERSAL_GND"
"1","(-1325,1950)","0","pure_quanta_power","I108";
;
CDS_LIB"pure_quanta_power"
HDL_POWER"GND";
"A"4;
%"MOSFET_N"
"1","(1900,1800)","0","pure_quanta","I109";
;
$LOCATION"U325"
CDS_LOCATION"U325"
$SEC"1"
CDS_SEC"1"
VALUE"BSS138K"
MANUF_PN"BSS138K"
PART_NUMBER"BAM138K0000"
MATERIAL"IC"
PACK_TYPE"SMLF"
CDS_LIB"pure_quanta"
CDS_LMAN_SYM_OUTLINE"-50,50,100,-150";
"GATE"
$PN"G"18;
"SOURCE"
$PN"S"5;
"DRAIN"
$PN"D"17;
%"UNIVERSAL_GND"
"1","(1950,1425)","0","pure_quanta_power","I111";
;
HDL_POWER"GND"
CDS_LIB"pure_quanta_power";
"A"5;
%"UNIVERSAL_POWER"
"1","(1950,2600)","0","pure_quanta_power","I113";
;
HDL_POWER"P3V3_AUX"
CDS_LIB"pure_quanta_power";
"A"6;
%"Q_RES"
"2","(1950,2375)","0","pure_quanta","I114";
;
$LOCATION"R4620"
CDS_LOCATION"R4620"
$SEC"1"
CDS_SEC"1"
PART_NUMBER"CS24702JB10"
WATTAGE"1/16W"
TOLERANCE"5%"
VALUE"4.7K"
PACK_TYPE"0402LF"
MATERIAL"CHIP"
CDS_LIB"pure_quanta";
"A"
$PN"1"6;
"B"
$PN"2"17;
%"Q_RES"
"2","(-2025,2200)","0","pure_quanta","I23";
;
LOCATION"R2221"
$SEC"1"
CDS_SEC"1"
PART_NUMBER"CS32672FB03"
PACK_TYPE"0402LF"
TOLERANCE"1%"
WATTAGE"1/16W"
VALUE"26.7K"
MATERIAL"CHIP"
CDS_LIB"pure_quanta";
"A"
$PN"1"8;
"B"
$PN"2"16;
%"Q_RES"
"2","(-2625,2200)","0","pure_quanta","I3";
;
LOCATION"R2219"
$SEC"1"
CDS_SEC"1"
VALUE"267K"
WATTAGE"1/16W"
TOLERANCE"1%"
MATERIAL"CHIP"
PACK_TYPE"0402LF"
PART_NUMBER"CS42672FB03"
CDS_LIB"pure_quanta";
"A"
$PN"1"7;
"B"
$PN"2"20;
%"UNIVERSAL_GND"
"1","(200,1475)","0","pure_quanta_power","I30";
;
HDL_POWER"GND"
CDS_LIB"pure_quanta_power";
"A"22;
%"Q_RES"
"2","(300,2175)","0","pure_quanta","I35";
;
LOCATION"R2230"
$SEC"1"
CDS_SEC"1"
VALUE"10K"
TOLERANCE"1%"
MATERIAL"CHIP"
PACK_TYPE"0402LF"
WATTAGE"1/16W"
CDS_LIB"pure_quanta"
PART_NUMBER"CS31002FB08";
"A"
$PN"1"23;
"B"
$PN"2"18;
%"Q_RES"
"2","(600,2200)","0","pure_quanta","I36";
;
LOCATION"R2233"
$SEC"1"
CDS_SEC"1"
VALUE"10K"
TOLERANCE"1%"
WATTAGE"1/16W"
MATERIAL"CHIP"
PACK_TYPE"0402LF"
CDS_LIB"pure_quanta"
PART_NUMBER"CS31002FB08";
"A"
$PN"1"23;
"B"
$PN"2"19;
%"UNIVERSAL_POWER"
"1","(-2625,2550)","0","pure_quanta_power","I4";
;
HDL_POWER"P12V_AUX"
CDS_LIB"pure_quanta_power";
"A"7;
%"UNIVERSAL_POWER"
"1","(-2025,2550)","0","pure_quanta_power","I41";
;
HDL_POWER"P12V_AUX"
CDS_LIB"pure_quanta_power";
"A"8;
%"UNIVERSAL_POWER"
"1","(-825,2550)","0","pure_quanta_power","I44";
;
HDL_POWER"P12V_AUX"
CDS_LIB"pure_quanta_power";
"A"21;
%"UNIVERSAL_POWER"
"1","(300,2550)","0","pure_quanta_power","I51";
;
HDL_POWER"P3V3_AUX"
CDS_LIB"pure_quanta_power";
"A"23;
%"LT6700CS61TRPBF"
"1","(-250,1750)","0","pure_quanta","I75";
;
$LOCATION"U206"
CDS_LOCATION"U206"
$SEC"1"
CDS_SEC"1"
PART_TYPE"SMLF"
VALUE"LT6700CS6-1#TRPBF"
PART_NUMBER"AL006700001"
MATERIAL"IC"
CDS_LIB"pure_quanta"
CDS_LMAN_SYM_OUTLINE"-225,150,225,-150"
NEEDS_NO_SIZE"TRUE";
"OUTB"
$PN"6"18;
"INA+"
$PN"3"20;
"OUTA"
$PN"1"19;
"GND"
$PN"2"22;
"INB-"
$PN"4"16;
"VS"
$PN"5"21;
%"Q_RES"
"2","(-2625,1450)","0","pure_quanta","I83";
;
LOCATION"R2227"
$SEC"1"
CDS_SEC"1"
TOLERANCE"1%"
VALUE"10K"
PACK_TYPE"0402LF"
WATTAGE"1/16W"
MATERIAL"CHIP"
PART_NUMBER"CS31002FB08"
CDS_LIB"pure_quanta";
"A"
$PN"1"20;
"B"
$PN"2"2;
%"Q_RES"
"2","(-2025,1450)","0","pure_quanta","I84";
;
LOCATION"R2222"
$SEC"1"
CDS_SEC"1"
TOLERANCE"1%"
VALUE"1K"
MATERIAL"CHIP"
PACK_TYPE"0402LF"
PART_NUMBER"CS21002FB06"
WATTAGE"1/16W"
CDS_LIB"pure_quanta";
"A"
$PN"1"16;
"B"
$PN"2"3;
%"LT6700CS61TRPBF"
"1","(-650,-400)","0","pure_quanta","I85";
;
$LOCATION"U205"
CDS_LOCATION"U205"
$SEC"1"
CDS_SEC"1"
PART_NUMBER"AL006700001"
MATERIAL"IC"
PART_TYPE"SMLF"
VALUE"LT6700CS6-1#TRPBF"
NEEDS_NO_SIZE"TRUE"
CDS_LMAN_SYM_OUTLINE"-225,150,225,-150"
CDS_LIB"pure_quanta";
"OUTB"
$PN"6"12;
"INA+"
$PN"3"15;
"OUTA"
$PN"1"13;
"GND"
$PN"2"24;
"INB-"
$PN"4"14;
"VS"
$PN"5"25;
%"UNIVERSAL_GND"
"1","(-200,-625)","0","pure_quanta_power","I90";
;
CDS_LIB"pure_quanta_power"
HDL_POWER"GND";
"A"24;
%"UNIVERSAL_GND"
"1","(-1725,-250)","0","pure_quanta_power","I91";
;
HDL_POWER"GND"
CDS_LIB"pure_quanta_power";
"A"9;
%"UNIVERSAL_POWER"
"1","(-1225,350)","0","pure_quanta_power","I93";
;
HDL_POWER"P3V3_AUX"
CDS_LIB"pure_quanta_power";
"A"25;
%"Q_RES"
"2","(-2500,-250)","0","pure_quanta","I95";
;
$LOCATION"R2238"
CDS_LOCATION"R2238"
$SEC"1"
CDS_SEC"1"
TOLERANCE"1%"
VALUE"4.99K"
PACK_TYPE"0402LF"
PART_NUMBER"CS24992FB07"
MATERIAL"CHIP"
WATTAGE"1/16W"
CDS_LIB"pure_quanta";
"A"
$PN"1"15;
"B"
$PN"2"1;
%"Q_RES"
"2","(-2500,150)","0","pure_quanta","I96";
;
LOCATION"R2236"
$SEC"1"
CDS_SEC"1"
MATERIAL"CHIP"
TOLERANCE"1%"
WATTAGE"1/16W"
PACK_TYPE"0402LF"
PART_NUMBER"CS41002FB09"
VALUE"100K"
CDS_LIB"pure_quanta";
"A"
$PN"1"10;
"B"
$PN"2"15;
%"UNIVERSAL_POWER"
"1","(-2500,400)","0","pure_quanta_power","I97";
;
HDL_POWER"P12V_AUX"
CDS_LIB"pure_quanta_power";
"A"10;
%"Q_RES"
"1","(1000,-350)","0","pure_quanta","I99";
;
LOCATION"R2330"
$SEC"1"
CDS_SEC"1"
WATTAGE"1/16W"
VALUE"0"
TOLERANCE"5%"
MATERIAL"EMPTY"
PART_NUMBER"CS00002JB13"
PACK_TYPE"0402LF"
CDS_LIB"pure_quanta";
"B"
$PN"2"11;
"A"
$PN"1"13;
END.
